(kicad_pcb
	(version 20260206)
	(generator "pcbnew")
	(generator_version "10.0")
	(general
		(thickness 1.6)
		(legacy_teardrops no)
	)
	(paper "A4")
	(title_block
		(title "03242023_DA0F0TMBIJ0_F0T_Motherboard_J_brd_V01_OCP.brd")
		(comment 1 "Grand Teton / footprint 1187 of 6105 (U249), pads 423-484 of 484")
	)
	(layers
		(0 "F.Cu" signal "TOP")
		(4 "In1.Cu" signal "GND")
		(6 "In2.Cu" signal "IN1")
		(8 "In3.Cu" signal "GND1")
		(10 "In4.Cu" signal "IN2")
		(12 "In5.Cu" signal "GND2")
		(14 "In6.Cu" signal "IN3")
		(16 "In7.Cu" signal "GND3")
		(18 "In8.Cu" signal "VCC")
		(20 "In9.Cu" signal "VCC1")
		(22 "In10.Cu" signal "GND4")
		(24 "In11.Cu" signal "IN4")
		(26 "In12.Cu" signal "GND5")
		(28 "In13.Cu" signal "IN5")
		(30 "In14.Cu" signal "GND6")
		(32 "In15.Cu" signal "IN6")
		(34 "In16.Cu" signal "GND7")
		(2 "B.Cu" signal "BOTTOM")
		(9 "F.Adhes" user "F.Adhesive")
		(11 "B.Adhes" user "B.Adhesive")
		(13 "F.Paste" user "Package Geometry/Pastemask Top")
		(15 "B.Paste" user "Package Geometry/Pastemask Bottom")
		(5 "F.SilkS" user "Ref Des/Silkscreen Top")
		(7 "B.SilkS" user "Ref Des/Silkscreen Bottom")
		(1 "F.Mask" user "Board Geometry/Soldermask Top")
		(3 "B.Mask" user "Board Geometry/Soldermask Bottom")
		(17 "Dwgs.User" user "User.Drawings")
		(19 "Cmts.User" user "User.Comments")
		(21 "Eco1.User" user "User.Eco1")
		(23 "Eco2.User" user "User.Eco2")
		(25 "Edge.Cuts" user "Board Geometry/Outline")
		(27 "Margin" user)
		(31 "F.CrtYd" user "Package Geometry/Place Bound Top")
		(29 "B.CrtYd" user "Package Geometry/Place Bound Bottom")
		(35 "F.Fab" user "Ref Des/Assembly Top")
		(33 "B.Fab" user "Ref Des/Assembly Bottom")
	)
	(footprint ""
		(layer "F.Cu")
		(at 178.55565 -113.37544 90)
		(property "Reference" "U249"
			(at -11.966194 -11.833098 0)
			(unlocked yes)
			(layer "F.SilkS")
			(effects
				(font
					(size 0.7874 0.5842)
					(thickness 0.1524)
				)
				(justify left)
			)
		)
		(property "Value" ""
			(at 0 0 90)
			(layer "F.Fab")
			(effects
				(font
					(size 1.27 1.27)
				)
			)
		)
		(duplicate_pad_numbers_are_jumpers no)
		(pad "V5" smd circle
			(at -5.199888 5.199888 90)
			(size 0.4064 0.4064)
			(layers "F.Cu" "F.Mask" "F.Paste")
			(net "H_CPU1_MEMHOT_IN_LVC1_R_N")
		)
		(pad "V6" smd circle
			(at -4.400042 5.199888 90)
			(size 0.4064 0.4064)
			(layers "F.Cu" "F.Mask" "F.Paste")
			(net "FM_ADR_TRIGGER_N")
		)
		(pad "V7" smd circle
			(at -3.599942 5.199888 90)
			(size 0.4064 0.4064)
			(layers "F.Cu" "F.Mask" "F.Paste")
			(net "RST_PFR_OVR_SRTC_R")
		)
		(pad "V8" smd circle
			(at -2.800096 5.199888 90)
			(size 0.4064 0.4064)
			(layers "F.Cu" "F.Mask" "F.Paste")
			(net "FM_REMOTE_DEBUG_DET")
		)
		(pad "V9" smd circle
			(at -1.999996 5.199888 90)
			(size 0.4064 0.4064)
			(layers "F.Cu" "F.Mask" "F.Paste")
			(net "FM_PS_PWROK_DLY_SEL")
		)
		(pad "V10" smd circle
			(at -1.199896 5.199888 90)
			(size 0.4064 0.4064)
			(layers "F.Cu" "F.Mask" "F.Paste")
			(net "E1S_0_PRSNT_N")
		)
		(pad "V11" smd circle
			(at -0.40005 5.199888 90)
			(size 0.4064 0.4064)
			(layers "F.Cu" "F.Mask" "F.Paste")
			(net "PRSNT_CABLE_GPU_A2_ISO_R_N")
		)
		(pad "V12" smd circle
			(at 0.40005 5.199888 90)
			(size 0.4064 0.4064)
			(layers "F.Cu" "F.Mask" "F.Paste")
			(net "GPU_3V3IO_RSVD4_ISO_R")
		)
		(pad "V13" smd circle
			(at 1.199896 5.199888 90)
			(size 0.4064 0.4064)
			(layers "F.Cu" "F.Mask" "F.Paste")
			(net "IRQ_PCH_CPU_NMI_EVENT_N")
		)
		(pad "V14" smd circle
			(at 1.999996 5.199888 90)
			(size 0.4064 0.4064)
			(layers "F.Cu" "F.Mask" "F.Paste")
			(net "NC_FPGA_PB32D")
		)
		(pad "V15" smd circle
			(at 2.800096 5.199888 90)
			(size 0.4064 0.4064)
			(layers "F.Cu" "F.Mask" "F.Paste")
			(net "ROT_P1_RST_IND_N_R")
		)
		(pad "V16" smd circle
			(at 3.599942 5.199888 90)
			(size 0.4064 0.4064)
			(layers "F.Cu" "F.Mask" "F.Paste")
			(net "RST_RSMRST_PLD_R_N")
		)
		(pad "V17" smd circle
			(at 4.400042 5.199888 90)
			(size 0.4064 0.4064)
			(layers "F.Cu" "F.Mask" "F.Paste")
			(net "FM_PDB_BUF_EN")
		)
		(pad "V18" smd circle
			(at 5.199888 5.199888 90)
			(size 0.4064 0.4064)
			(layers "F.Cu" "F.Mask" "F.Paste")
			(net "FM_BMC_CPU_FBRK_OUT_R_N")
		)
		(pad "V19" smd circle
			(at 5.999988 5.199888 90)
			(size 0.4064 0.4064)
			(layers "F.Cu" "F.Mask" "F.Paste")
			(net "CLK_GEN2_GPU_FPGA_OE_R_N")
		)
		(pad "V20" smd circle
			(at 6.800088 5.199888 90)
			(size 0.4064 0.4064)
			(layers "F.Cu" "F.Mask" "F.Paste")
			(net "P3V3_AUX_FPGA_VCCIO1")
		)
		(pad "V21" smd circle
			(at 7.599934 5.199888 90)
			(size 0.4064 0.4064)
			(layers "F.Cu" "F.Mask" "F.Paste")
			(net "GND")
		)
		(pad "V22" smd circle
			(at 8.400034 5.199888 90)
			(size 0.4064 0.4064)
			(layers "F.Cu" "F.Mask" "F.Paste")
			(net "FM_PS_EN_PLD_R")
		)
		(pad "W1" smd circle
			(at -8.400034 5.999988 90)
			(size 0.4064 0.4064)
			(layers "F.Cu" "F.Mask" "F.Paste")
			(net "PWRGD_CPU1_LVC1_R")
		)
		(pad "W2" smd circle
			(at -7.599934 5.999988 90)
			(size 0.4064 0.4064)
			(layers "F.Cu" "F.Mask" "F.Paste")
			(net "PWRGD_CPU0_LVC1_R")
		)
		(pad "W3" smd circle
			(at -6.800088 5.999988 90)
			(size 0.4064 0.4064)
			(layers "F.Cu" "F.Mask" "F.Paste")
			(net "FM_THERMTRIP_DLY_LVC1_R_N")
		)
		(pad "W4" smd circle
			(at -5.999988 5.999988 90)
			(size 0.4064 0.4064)
			(layers "F.Cu" "F.Mask" "F.Paste")
			(net "H_CPU0_PROCHOT_LVC1_R_N")
		)
		(pad "W5" smd circle
			(at -5.199888 5.999988 90)
			(size 0.4064 0.4064)
			(layers "F.Cu" "F.Mask" "F.Paste")
			(net "NC_FPGA_PB7D")
		)
		(pad "W6" smd circle
			(at -4.400042 5.999988 90)
			(size 0.4064 0.4064)
			(layers "F.Cu" "F.Mask" "F.Paste")
			(net "RST_PFR_OVR_RTC_R")
		)
		(pad "W7" smd circle
			(at -3.599942 5.999988 90)
			(size 0.4064 0.4064)
			(layers "F.Cu" "F.Mask" "F.Paste")
			(net "P3V3_AUX_FPGA_VCCIO2")
		)
		(pad "W8" smd circle
			(at -2.800096 5.999988 90)
			(size 0.4064 0.4064)
			(layers "F.Cu" "F.Mask" "F.Paste")
			(net "FM_RST_PERST_BIT2")
		)
		(pad "W9" smd circle
			(at -1.999996 5.999988 90)
			(size 0.4064 0.4064)
			(layers "F.Cu" "F.Mask" "F.Paste")
			(net "USB_OC1_REAR_N")
		)
		(pad "W10" smd circle
			(at -1.199896 5.999988 90)
			(size 0.4064 0.4064)
			(layers "F.Cu" "F.Mask" "F.Paste")
			(net "HSC_D_OC_R1")
		)
		(pad "W11" smd circle
			(at -0.40005 5.999988 90)
			(size 0.4064 0.4064)
			(layers "F.Cu" "F.Mask" "F.Paste")
			(net "P3V3_AUX_FPGA_VCCIO2")
		)
		(pad "W12" smd circle
			(at 0.40005 5.999988 90)
			(size 0.4064 0.4064)
			(layers "F.Cu" "F.Mask" "F.Paste")
			(net "GND")
		)
		(pad "W13" smd circle
			(at 1.199896 5.999988 90)
			(size 0.4064 0.4064)
			(layers "F.Cu" "F.Mask" "F.Paste")
			(net "IRQ_PCH_SCI_WHEA_R_N")
		)
		(pad "W14" smd circle
			(at 1.999996 5.999988 90)
			(size 0.4064 0.4064)
			(layers "F.Cu" "F.Mask" "F.Paste")
			(net "FM_BIOS_DEBUG_EN_N")
		)
		(pad "W15" smd circle
			(at 2.800096 5.999988 90)
			(size 0.4064 0.4064)
			(layers "F.Cu" "F.Mask" "F.Paste")
			(net "FM_DIMM_12V_CPS_SX_N")
		)
		(pad "W16" smd circle
			(at 3.599942 5.999988 90)
			(size 0.4064 0.4064)
			(layers "F.Cu" "F.Mask" "F.Paste")
			(net "P3V3_AUX_FPGA_VCCIO2")
		)
		(pad "W17" smd circle
			(at 4.400042 5.999988 90)
			(size 0.4064 0.4064)
			(layers "F.Cu" "F.Mask" "F.Paste")
			(net "CLK_SWB_OE_N")
		)
		(pad "W18" smd circle
			(at 5.199888 5.999988 90)
			(size 0.4064 0.4064)
			(layers "F.Cu" "F.Mask" "F.Paste")
			(net "SWB_HSC_PWRGD_ISO_R")
		)
		(pad "W19" smd circle
			(at 5.999988 5.999988 90)
			(size 0.4064 0.4064)
			(layers "F.Cu" "F.Mask" "F.Paste")
			(net "RST_PERST_SWB_N")
		)
		(pad "W20" smd circle
			(at 6.800088 5.999988 90)
			(size 0.4064 0.4064)
			(layers "F.Cu" "F.Mask" "F.Paste")
			(net "FM_PCH_SPKR_R")
		)
		(pad "W21" smd circle
			(at 7.599934 5.999988 90)
			(size 0.4064 0.4064)
			(layers "F.Cu" "F.Mask" "F.Paste")
			(net "FM_SMB_1_ALERT_GPU_ISO_R_N")
		)
		(pad "W22" smd circle
			(at 8.400034 5.999988 90)
			(size 0.4064 0.4064)
			(layers "F.Cu" "F.Mask" "F.Paste")
			(net "PWRGD_FAIL_CPU0_AB_R")
		)
		(pad "Y1" smd circle
			(at -8.400034 6.800088 90)
			(size 0.4064 0.4064)
			(layers "F.Cu" "F.Mask" "F.Paste")
			(net "H_CPU_RMCA_LVC2_R2_N")
		)
		(pad "Y2" smd circle
			(at -7.599934 6.800088 90)
			(size 0.4064 0.4064)
			(layers "F.Cu" "F.Mask" "F.Paste")
			(net "H_CPU_CATERR_LVC2_R2_N")
		)
		(pad "Y3" smd circle
			(at -6.800088 6.800088 90)
			(size 0.4064 0.4064)
			(layers "F.Cu" "F.Mask" "F.Paste")
			(net "H_CPU1_PROCHOT_LVC1_R_N")
		)
		(pad "Y4" smd circle
			(at -5.999988 6.800088 90)
			(size 0.4064 0.4064)
			(layers "F.Cu" "F.Mask" "F.Paste")
			(net "IRQ_UV_DETECT_R_N")
		)
		(pad "Y5" smd circle
			(at -5.199888 6.800088 90)
			(size 0.4064 0.4064)
			(layers "F.Cu" "F.Mask" "F.Paste")
			(net "PCIE_M2_SSD0_PRSNT_N")
		)
		(pad "Y6" smd circle
			(at -4.400042 6.800088 90)
			(size 0.4064 0.4064)
			(layers "F.Cu" "F.Mask" "F.Paste")
			(net "FM_HBM2_HBM3_VPP_SEL")
		)
		(pad "Y7" smd circle
			(at -3.599942 6.800088 90)
			(size 0.4064 0.4064)
			(layers "F.Cu" "F.Mask" "F.Paste")
			(net "GND")
		)
		(pad "Y8" smd circle
			(at -2.800096 6.800088 90)
			(size 0.4064 0.4064)
			(layers "F.Cu" "F.Mask" "F.Paste")
			(net "FM_ME_AUTHN_FAIL")
		)
		(pad "Y9" smd circle
			(at -1.999996 6.800088 90)
			(size 0.4064 0.4064)
			(layers "F.Cu" "F.Mask" "F.Paste")
			(net "PRSNT_SWB_ISO_R_N")
		)
		(pad "Y10" smd circle
			(at -1.199896 6.800088 90)
			(size 0.4064 0.4064)
			(layers "F.Cu" "F.Mask" "F.Paste")
			(net "FM_PCH_BMC_RST_N")
		)
		(pad "Y11" smd circle
			(at -0.40005 6.800088 90)
			(size 0.4064 0.4064)
			(layers "F.Cu" "F.Mask" "F.Paste")
			(net "GPU_3V3IO_RSVD5_FFU_ISO_R")
		)
		(pad "Y12" smd circle
			(at 0.40005 6.800088 90)
			(size 0.4064 0.4064)
			(layers "F.Cu" "F.Mask" "F.Paste")
			(net "PRSNT_CABLE_GPU_A1_ISO_R_N")
		)
		(pad "Y13" smd circle
			(at 1.199896 6.800088 90)
			(size 0.4064 0.4064)
			(layers "F.Cu" "F.Mask" "F.Paste")
			(net "IRQ_PSU_ALERT_R_N")
		)
		(pad "Y14" smd circle
			(at 1.999996 6.800088 90)
			(size 0.4064 0.4064)
			(layers "F.Cu" "F.Mask" "F.Paste")
			(net "FM_NCSI_OCP_V3_1_R_OE")
		)
		(pad "Y15" smd circle
			(at 2.800096 6.800088 90)
			(size 0.4064 0.4064)
			(layers "F.Cu" "F.Mask" "F.Paste")
			(net "FM_THROTTLE_R_N")
		)
		(pad "Y16" smd circle
			(at 3.599942 6.800088 90)
			(size 0.4064 0.4064)
			(layers "F.Cu" "F.Mask" "F.Paste")
			(net "GND")
		)
		(pad "Y17" smd circle
			(at 4.400042 6.800088 90)
			(size 0.4064 0.4064)
			(layers "F.Cu" "F.Mask" "F.Paste")
			(net "RST_PLTRST_PLD_N")
		)
		(pad "Y18" smd circle
			(at 5.199888 6.800088 90)
			(size 0.4064 0.4064)
			(layers "F.Cu" "F.Mask" "F.Paste")
			(net "CLK_GPU_2_OE_N")
		)
		(pad "Y19" smd circle
			(at 5.999988 6.800088 90)
			(size 0.4064 0.4064)
			(layers "F.Cu" "F.Mask" "F.Paste")
			(net "SWB_HSC_EN_R")
		)
		(pad "Y20" smd circle
			(at 6.800088 6.800088 90)
			(size 0.4064 0.4064)
			(layers "F.Cu" "F.Mask" "F.Paste")
			(net "NC_FPGA_PR30D")
		)
		(pad "Y21" smd circle
			(at 7.599934 6.800088 90)
			(size 0.4064 0.4064)
			(layers "F.Cu" "F.Mask" "F.Paste")
			(net "GPU_FPGA_RST_N")
		)
		(pad "Y22" smd circle
			(at 8.400034 6.800088 90)
			(size 0.4064 0.4064)
			(layers "F.Cu" "F.Mask" "F.Paste")
			(net "HP_LVC3_OCP_V3_1_HSC_PWRGD_PLD_")
		)
	)
)
